;LEADER: 12 
;HEADER: 
;CODE  : ASCII 
;FILE  : 9324_DA0F0TMBIJ0_F0T_Motherboard_J_v01_20230324_0910-bd-18-13.drl for backdrilling ... from layer BOTTOM to layer GND5
;DESIGN: 9324_DA0F0TMBIJ0_F0T_Motherboard_J_v01_20230324_0910.brd
;MUST-NOT-CUT-LAYER = IN4,  MAX_DRILL_DEPTH = 31.20 MILS,  MFG_STUB_LENGTH = 0.00 MILS
;   BackdrillSize 1. = 15.700000 Tolerance = +0.000000/-0.000000 NON_PLATED MILS Quantity = 1120
;   BackdrillSize 2. = 17.700000 Tolerance = +0.000000/-0.000000 NON_PLATED MILS Quantity = 196
;   BackdrillSize 3. = 21.870000 Tolerance = +0.000000/-0.000000 NON_PLATED MILS Quantity = 128
%
G90
X0066099Y1195144
X0066099Y1191798
X0066099Y1201837
X0066099Y1208530
X0066099Y1185105
X0066099Y1084711
X0066099Y1121522
X0066099Y1158333
X0066099Y1118176
X0066099Y1154987
X0066099Y1104790
X0066099Y1111483
X0066099Y1128215
X0066099Y1134908
X0066099Y1141601
X0066099Y1148294
X0066099Y1165026
X0066099Y1171719
X0066099Y1178412
X0066099Y1091404
X0066099Y1098097
X0066099Y0987664
X0066099Y0994357
X0066099Y1021129
X0066099Y1081365
X0066099Y1054593
X0052541Y1051247
X0036399Y1054593
X0066099Y1067979
X0066099Y1074672
X0066099Y1027822
X0066099Y1034515
X0066099Y1041207
X0066099Y1047900
X0052541Y1024475
X0052541Y1021129
X0066099Y0937467
X0066099Y0900656
X0066099Y0934121
X0066099Y0897310
X0066099Y0883924
X0066099Y0890617
X0066099Y0907349
X0066099Y0914042
X0066099Y0944160
X0066099Y0950853
X0066099Y0920735
X0066099Y0927428
X0066099Y0974278
X0066099Y0980971
X0066099Y0790223
X0066099Y0863845
X0066099Y0786877
X0066099Y0860499
X0066099Y0870538
X0066099Y0877231
X0066099Y0796916
X0066099Y0803609
X0066099Y0847113
X0066099Y0853806
X0066099Y0773491
X0066099Y0780184
X0082241Y0783530
X0082241Y0770144
X0082241Y0776837
X0082241Y0857152
X0082241Y0786877
X0082241Y0860499
X0082241Y0880577
X0082241Y0793570
X0082241Y0800263
X0082241Y0843766
X0082241Y0850459
X0082241Y0867192
X0082241Y0873885
X0082241Y0970932
X0082241Y0893963
X0082241Y0930774
X0082241Y0897310
X0082241Y0934121
X0082241Y0887270
X0082241Y0904003
X0082241Y0910696
X0082241Y0940814
X0082241Y0947507
X0082241Y0917389
X0082241Y0924081
X0082241Y0977625
X0082241Y0984318
X0082241Y0991011
X0082241Y1078018
X0082241Y1081365
X0082241Y1051247
X0082241Y1064633
X0082241Y1071326
X0082241Y1031168
X0082241Y1037861
X0082241Y1044554
X0082241Y1024475
X0082241Y1021129
X0082241Y1114829
X0082241Y1151641
X0082241Y1118176
X0082241Y1154987
X0082241Y1101444
X0082241Y1108137
X0082241Y1124869
X0082241Y1131562
X0082241Y1138255
X0082241Y1144948
X0082241Y1161680
X0082241Y1168373
X0082241Y1175066
X0082241Y1181759
X0082241Y1088058
X0082241Y1094751
X0082241Y1188452
X0082241Y1191798
X0082241Y1198491
X0082241Y1205184
X0367812Y1111834
X0369661Y1115039
X0365961Y1108630
X0358561Y1115039
X0362261Y1108630
X0345611Y1124651
X0347461Y1127856
X0341911Y1131060
X0343761Y1121447
X0340061Y1121447
X0369661Y1108630
X0365961Y1115039
X0364112Y1105426
X0360412Y1111834
X0358561Y1108630
X0347461Y1121447
X0343761Y1127856
X0340061Y1127856
X0341912Y1118243
X0336361Y1121447
X0415911Y1105426
X0419611Y1111834
X0412211Y1105426
X0414062Y1115039
X0408511Y1111834
X0410362Y1108630
X0401111Y1111834
X0402962Y1115039
X0399262Y1108630
X0391862Y1115039
X0395562Y1108630
X0402962Y1102221
X0408511Y1099017
X0419611Y1105426
X0417762Y1108630
X0414062Y1102221
X0415911Y1111834
X0412211Y1111834
X0408511Y1105426
X0402962Y1108630
X0399262Y1115039
X0397411Y1105426
X0393711Y1111834
X0391862Y1108630
X0401111Y1099017
X0404811Y1099017
X0397411Y1092608
X0390011Y1092608
X0393711Y1092608
X0386311Y1092608
X0388162Y1095813
X0390011Y1099017
X0393711Y1086200
X0395562Y1089404
X0390011Y1086200
X0388162Y1089404
X0395562Y1095813
X0393711Y1099017
X0430711Y1079791
X0428861Y1076587
X0397411Y1034931
X0397411Y1054157
X0397411Y1073383
X0390011Y1034931
X0390011Y1054157
X0390011Y1073383
X0393711Y1034931
X0393711Y1054157
X0393711Y1073383
X0386311Y1034931
X0386311Y1054157
X0386311Y1073383
X0393711Y1047749
X0395562Y1050952
X0390011Y1047749
X0388162Y1050952
X0395562Y1057361
X0393711Y1060565
X0388162Y1057361
X0390011Y1060565
X0393711Y1066974
X0395562Y1070178
X0390011Y1066974
X0388162Y1070178
X0395562Y1076587
X0393711Y1079791
X0388162Y1076587
X0390011Y1079791
X0395562Y1018910
X0393711Y1022114
X0388162Y1018910
X0390011Y1022114
X0393711Y1028523
X0395562Y1031727
X0390011Y1028523
X0388162Y1031727
X0395562Y1038136
X0393711Y1041340
X0388162Y1038136
X0390011Y1041340
X0393711Y1009297
X0390011Y1009297
X0395562Y1012501
X0388162Y1012501
X0397411Y1015705
X0386311Y1015705
X0384029Y0973143
X0389578Y0963530
X0396978Y0905853
X0396978Y0925079
X0396978Y0944304
X0393278Y0963530
X0389578Y0905853
X0389578Y0925079
X0389578Y0944304
X0385878Y0963530
X0393278Y0905853
X0393278Y0925079
X0393278Y0944304
X0396978Y0963530
X0385878Y0905853
X0385878Y0925079
X0385878Y0944304
X0387729Y0928283
X0389578Y0931488
X0393278Y0937896
X0395129Y0941100
X0389578Y0937896
X0387729Y0941100
X0395129Y0947509
X0393278Y0899445
X0395129Y0902649
X0393278Y0950713
X0389578Y0899445
X0387729Y0902649
X0395129Y0909057
X0393278Y0912262
X0387729Y0909057
X0389578Y0912262
X0387729Y0947509
X0393278Y0918670
X0395129Y0921875
X0389578Y0918670
X0387729Y0921875
X0395129Y0928283
X0393278Y0931488
X0389578Y0950713
X0395129Y0966735
X0393278Y0969939
X0387729Y0966735
X0389578Y0969939
X0393278Y0957122
X0395129Y0960326
X0389578Y0957122
X0387729Y0960326
X0372929Y0973143
X0382178Y0976347
X0374778Y0976347
X0380329Y0979552
X0376629Y0979552
X0389579Y0976347
X0387729Y0979552
X0395129Y0979552
X0393278Y0976347
X0396978Y0982756
X0389578Y0982756
X0393278Y0982756
X0385878Y0982756
X0435829Y0870606
X0437678Y0867401
X0443229Y0870606
X0445078Y0867401
X0450629Y0870606
X0452478Y0867401
X0458029Y0870606
X0459878Y0867401
X0465429Y0870606
X0413629Y0870606
X0415478Y0867401
X0421029Y0870606
X0422878Y0867401
X0428429Y0870606
X0430278Y0867401
X0467278Y0867401
X0433979Y0873810
X0439529Y0870606
X0441378Y0873810
X0446929Y0870606
X0448779Y0873810
X0454329Y0870606
X0456178Y0873810
X0461729Y0870606
X0463578Y0873810
X0411778Y0873810
X0417329Y0870606
X0419178Y0873810
X0424729Y0870606
X0426578Y0873810
X0432129Y0870606
X0469129Y0870606
X0507978Y0963530
X0483929Y0953917
X0495029Y0896240
X0491329Y0915466
X0491329Y0934691
X0491329Y0953917
X0487629Y0896240
X0483929Y0915466
X0483929Y0934691
X0487629Y0953917
X0491329Y0896240
X0495029Y0915466
X0495029Y0934691
X0495029Y0953917
X0483929Y0896240
X0487629Y0915466
X0487629Y0934691
X0485778Y0918670
X0487629Y0921875
X0487629Y0928283
X0493178Y0931488
X0491329Y0928283
X0485778Y0931488
X0493178Y0937896
X0485778Y0893036
X0496878Y0893036
X0491329Y0941100
X0482078Y0893036
X0493178Y0893036
X0493178Y0899445
X0491329Y0902649
X0485778Y0899445
X0487629Y0902649
X0485778Y0937896
X0491329Y0909057
X0493178Y0912262
X0487629Y0909057
X0485778Y0912262
X0493178Y0918670
X0491329Y0921875
X0487629Y0941100
X0485778Y0957122
X0487629Y0960326
X0493178Y0957122
X0491329Y0960326
X0491329Y0947509
X0493178Y0950713
X0487629Y0947509
X0485778Y0950713
X0496878Y0963530
X0506129Y0966735
X0498729Y0966735
X0504278Y0969939
X0500578Y0969939
X0493178Y0969939
X0491329Y0966735
X0487629Y0966735
X0485778Y0969939
X0483929Y0973143
X0491329Y0973143
X0487629Y0973143
X0495029Y0973143
X0491762Y1025318
X0491762Y1044544
X0491762Y1063770
X0491762Y1082995
X0484362Y1025318
X0484362Y1044544
X0484362Y1063770
X0488062Y1082995
X0495462Y1025318
X0495462Y1044544
X0495462Y1063770
X0495462Y1082995
X0488062Y1025318
X0488062Y1044544
X0488062Y1063770
X0484362Y1082995
X0491762Y1038136
X0493611Y1041340
X0488062Y1038136
X0486211Y1041340
X0493611Y1047749
X0491762Y1050952
X0486211Y1047749
X0488062Y1050952
X0491762Y1057361
X0493611Y1060565
X0488062Y1057361
X0486211Y1060565
X0493611Y1066974
X0491762Y1070178
X0486211Y1066974
X0488062Y1070178
X0491762Y1076587
X0493611Y1079791
X0488062Y1076587
X0486211Y1079791
X0486211Y1009297
X0488062Y1012501
X0493611Y1009297
X0491761Y1012501
X0491762Y1018910
X0493611Y1022114
X0488062Y1018910
X0486211Y1022114
X0493611Y1028523
X0491762Y1031727
X0486211Y1028523
X0488062Y1031727
X0491762Y0999684
X0488062Y0999684
X0493611Y1002888
X0486211Y1002888
X0495462Y1006093
X0484362Y1006093
X0486211Y1086200
X0488062Y1089404
X0493611Y1086200
X0491762Y1089404
X0815241Y1188451
X0799099Y1195144
X0815241Y1191798
X0799099Y1191798
X0799099Y1201837
X0799099Y1208530
X0799099Y1185105
X0815241Y1198491
X0815241Y1205184
X0815241Y1114829
X0815241Y1151640
X0799099Y1084711
X0799099Y1121522
X0799099Y1158333
X0815241Y1118176
X0815241Y1154987
X0799099Y1118176
X0799099Y1154987
X0815241Y1101444
X0815241Y1108136
X0799099Y1104790
X0799099Y1111483
X0815241Y1124869
X0815241Y1131562
X0799099Y1128215
X0799099Y1134908
X0815241Y1138255
X0815241Y1144947
X0799099Y1141601
X0799099Y1148294
X0815241Y1161680
X0815241Y1168373
X0799099Y1165026
X0799099Y1171719
X0815241Y1175066
X0815241Y1181758
X0799099Y1178412
X0815241Y1088058
X0815241Y1094751
X0799099Y1091404
X0799099Y1098097
X0815241Y0984318
X0799099Y0987664
X0815241Y0991011
X0799099Y0994357
X0799099Y1021129
X0815241Y1078018
X0815241Y1081365
X0799099Y1081365
X0814941Y1051247
X0799099Y1054593
X0844941Y1051247
X0828799Y1054593
X0815241Y1064633
X0815241Y1071325
X0799099Y1067979
X0799099Y1074672
X0799099Y1027822
X0815241Y1031168
X0799099Y1034515
X0815241Y1037861
X0799099Y1041207
X0815241Y1044554
X0799099Y1047900
X0815241Y1024475
X0844941Y1024475
X0815241Y1021129
X0844941Y1021129
X0815241Y0970932
X0799099Y0937467
X0815241Y0893963
X0815241Y0930774
X0799099Y0900656
X0799099Y0934121
X0815241Y0897310
X0815241Y0934121
X0799099Y0897310
X0815241Y0887270
X0799099Y0883924
X0799099Y0890617
X0815241Y0904003
X0815241Y0910696
X0799099Y0907349
X0799099Y0914042
X0815241Y0940814
X0815241Y0947507
X0799099Y0944160
X0799099Y0950853
X0815241Y0917389
X0815241Y0924081
X0799099Y0920735
X0799099Y0927428
X0799099Y0974278
X0815241Y0977625
X0799099Y0980971
X0815241Y0857152
X0799099Y0790223
X0799099Y0863845
X0815241Y0786877
X0815241Y0860499
X0799099Y0786877
X0799099Y0860499
X0799099Y0870538
X0799099Y0877231
X0815241Y0880577
X0815241Y0793570
X0815241Y0800263
X0799099Y0796916
X0799099Y0803609
X0815241Y0843766
X0815241Y0850459
X0799099Y0847113
X0799099Y0853806
X0815241Y0867192
X0815241Y0873885
X0815241Y0783530
X0815241Y0770144
X0815241Y0776837
X0799099Y0773491
X0799099Y0780184
X1058383Y1188452
X1042241Y1195144
X1058383Y1191798
X1042241Y1191798
X1042241Y1201837
X1042241Y1208530
X1042241Y1185105
X1058383Y1198491
X1058383Y1205184
X1058383Y1114829
X1058383Y1151641
X1042241Y1084711
X1042241Y1121522
X1042241Y1158333
X1058383Y1118176
X1058383Y1154987
X1042241Y1118176
X1042241Y1154987
X1058383Y1101444
X1058383Y1108137
X1042241Y1104790
X1042241Y1111483
X1058383Y1124869
X1058383Y1131562
X1042241Y1128215
X1042241Y1134908
X1058383Y1138255
X1058383Y1144948
X1042241Y1141601
X1042241Y1148294
X1058383Y1161680
X1058383Y1168373
X1042241Y1165026
X1042241Y1171719
X1058383Y1175066
X1058383Y1181759
X1042241Y1178412
X1058383Y1088058
X1058383Y1094751
X1042241Y1091404
X1042241Y1098097
X1058383Y0984318
X1042241Y0987664
X1058383Y0991011
X1042241Y0994357
X1042241Y1021129
X1058383Y1078018
X1058383Y1081365
X1042241Y1081365
X1058383Y1051247
X1042241Y1054593
X1028683Y1051247
X1012541Y1054593
X1058383Y1064633
X1058383Y1071326
X1042241Y1067979
X1042241Y1074672
X1042241Y1027822
X1058383Y1031168
X1042241Y1034515
X1058383Y1037861
X1042241Y1041207
X1058383Y1044554
X1042241Y1047900
X1058383Y1024475
X1028683Y1024475
X1058383Y1021129
X1028683Y1021129
X1058383Y0970932
X1042241Y0937467
X1058383Y0893963
X1058383Y0930774
X1042241Y0900656
X1042241Y0934121
X1058383Y0897310
X1058383Y0934121
X1042241Y0897310
X1058383Y0887270
X1042241Y0883924
X1042241Y0890617
X1058383Y0904003
X1058383Y0910696
X1042241Y0907349
X1042241Y0914042
X1058383Y0940814
X1058383Y0947507
X1042241Y0944160
X1042241Y0950853
X1058383Y0917389
X1058383Y0924081
X1042241Y0920735
X1042241Y0927428
X1042241Y0974278
X1058383Y0977625
X1042241Y0980971
X1058383Y0857152
X1042241Y0790223
X1042241Y0863845
X1058383Y0786877
X1058383Y0860499
X1042241Y0786877
X1042241Y0860499
X1042241Y0870538
X1042241Y0877231
X1058383Y0880577
X1058383Y0793570
X1058383Y0800263
X1042241Y0796916
X1042241Y0803609
X1058383Y0843766
X1058383Y0850459
X1042241Y0847113
X1042241Y0853806
X1058383Y0867192
X1058383Y0873885
X1058383Y0783530
X1058383Y0770144
X1058383Y0776837
X1042241Y0773491
X1042241Y0780184
X1360171Y0973143
X1365720Y0963530
X1369420Y0963530
X1365720Y0905853
X1365720Y0925079
X1365720Y0944304
X1362020Y0963530
X1369420Y0905853
X1369420Y0925079
X1369420Y0944304
X1362020Y0905853
X1362020Y0925079
X1362020Y0944304
X1363871Y0928283
X1365720Y0931488
X1369420Y0937896
X1371271Y0941100
X1365720Y0937896
X1363871Y0941100
X1371271Y0947509
X1369420Y0899445
X1371271Y0902649
X1369420Y0950713
X1365720Y0899445
X1363871Y0902649
X1371271Y0909057
X1369420Y0912262
X1363871Y0909057
X1365720Y0912262
X1363871Y0947509
X1369420Y0918670
X1371271Y0921875
X1365720Y0918670
X1363871Y0921875
X1371271Y0928283
X1369420Y0931488
X1365720Y0950713
X1371271Y0966735
X1369420Y0969939
X1363871Y0966735
X1365720Y0969939
X1369420Y0957122
X1371271Y0960326
X1365720Y0957122
X1363871Y0960326
X1349071Y0973143
X1358320Y0976347
X1350920Y0976347
X1356471Y0979552
X1352771Y0979552
X1365721Y0976347
X1363871Y0979552
X1371271Y0979552
X1369420Y0976347
X1365720Y0982756
X1369420Y0982756
X1362020Y0982756
X1366153Y1034931
X1366153Y1054157
X1366153Y1073383
X1369853Y1034931
X1369853Y1054157
X1369853Y1073383
X1362453Y1034931
X1362453Y1054157
X1362453Y1073383
X1369853Y1047749
X1371704Y1050952
X1366153Y1047749
X1364304Y1050952
X1371704Y1057361
X1369853Y1060565
X1364304Y1057361
X1366153Y1060565
X1369853Y1066974
X1371704Y1070178
X1366153Y1066974
X1364304Y1070178
X1371704Y1076587
X1369853Y1079791
X1364304Y1076587
X1366153Y1079791
X1371704Y1018910
X1369853Y1022114
X1364304Y1018910
X1366153Y1022114
X1369853Y1028523
X1371704Y1031727
X1366153Y1028523
X1364304Y1031727
X1371704Y1038136
X1369853Y1041340
X1364304Y1038136
X1366153Y1041340
X1369853Y1009297
X1366153Y1009297
X1371704Y1012501
X1364304Y1012501
X1362453Y1015705
X1321753Y1105426
X1319904Y1108630
X1323603Y1115039
X1331003Y1102221
X1329154Y1111834
X1327304Y1108630
X1355054Y1105426
X1353204Y1108630
X1356904Y1102221
X1355053Y1111834
X1360604Y1108630
X1358753Y1111834
X1318053Y1105426
X1318054Y1111834
X1321753Y1111834
X1327303Y1102221
X1325454Y1111834
X1329153Y1105426
X1351353Y1105426
X1351353Y1111834
X1358753Y1105426
X1356904Y1115039
X1362453Y1105426
X1362453Y1111834
X1366153Y1092608
X1369853Y1092608
X1362453Y1092608
X1364304Y1095813
X1366153Y1099017
X1369853Y1086200
X1371704Y1089404
X1366153Y1086200
X1364304Y1089404
X1371704Y1095813
X1369853Y1099017
X1384653Y1092608
X1386504Y1089404
X1380953Y1086200
X1395753Y1092608
X1401304Y1095813
X1403153Y1092608
X1395753Y1086200
X1406852Y1086200
X1403154Y1086200
X1382804Y1089404
X1390204Y1089404
X1379103Y1089404
X1397604Y1089404
X1399453Y1092608
X1406853Y1092608
X1399453Y1086200
X1405003Y1089404
X1388353Y1086200
X1462353Y1086200
X1464204Y1089404
X1469753Y1086200
X1467904Y1089404
X1373553Y1092608
X1384653Y1079791
X1382804Y1082995
X1390204Y1082995
X1401304Y1082995
X1386504Y1082995
X1379104Y1082995
X1467904Y1025318
X1467904Y1044544
X1467904Y1063770
X1467904Y1082995
X1460504Y1025318
X1460504Y1044544
X1460504Y1063770
X1464204Y1082995
X1471604Y1025318
X1471604Y1044544
X1471604Y1063770
X1471604Y1082995
X1464204Y1025318
X1464204Y1044544
X1464204Y1063770
X1460504Y1082995
X1467904Y1038136
X1469753Y1041340
X1464204Y1038136
X1462353Y1041340
X1469753Y1047749
X1467904Y1050952
X1462353Y1047749
X1464204Y1050952
X1467904Y1057361
X1469753Y1060565
X1464204Y1057361
X1462353Y1060565
X1469753Y1066974
X1467904Y1070178
X1462353Y1066974
X1464204Y1070178
X1467904Y1076587
X1469753Y1079791
X1464204Y1076587
X1462353Y1079791
X1462353Y1009297
X1464204Y1012501
X1469753Y1009297
X1467903Y1012501
X1467904Y1018910
X1469753Y1022114
X1464204Y1018910
X1462353Y1022114
X1469753Y1028523
X1467904Y1031727
X1462353Y1028523
X1464204Y1031727
X1467904Y0999684
X1464204Y0999684
X1469753Y1002888
X1462353Y1002888
X1471604Y1006093
X1460504Y1006093
X1373553Y1034931
X1373553Y1054157
X1373553Y1073383
X1373553Y1015705
X1460071Y0953917
X1471171Y0896240
X1467471Y0915466
X1467471Y0934691
X1467471Y0953917
X1463771Y0896240
X1460071Y0915466
X1460071Y0934691
X1463771Y0953917
X1467471Y0896240
X1471171Y0915466
X1471171Y0934691
X1471171Y0953917
X1460071Y0896240
X1463771Y0915466
X1463771Y0934691
X1461920Y0918670
X1463771Y0921875
X1463771Y0928283
X1469320Y0931488
X1467471Y0928283
X1461920Y0931488
X1469320Y0937896
X1461920Y0893036
X1467471Y0941100
X1458220Y0893036
X1469320Y0893036
X1469320Y0899445
X1467471Y0902649
X1461920Y0899445
X1463771Y0902649
X1461920Y0937896
X1467471Y0909057
X1469320Y0912262
X1463771Y0909057
X1461920Y0912262
X1469320Y0918670
X1467471Y0921875
X1463771Y0941100
X1461920Y0957122
X1463771Y0960326
X1469320Y0957122
X1467471Y0960326
X1467471Y0947509
X1469320Y0950713
X1463771Y0947509
X1461920Y0950713
X1469320Y0969939
X1467471Y0966735
X1463771Y0966735
X1461920Y0969939
X1460071Y0973143
X1467471Y0973143
X1463771Y0973143
X1471171Y0973143
X1373120Y0905853
X1373120Y0925079
X1373120Y0944304
X1373120Y0963530
X1373120Y0982756
X1411971Y0870606
X1413820Y0867401
X1419371Y0870606
X1421220Y0867401
X1426771Y0870606
X1428620Y0867401
X1434171Y0870606
X1436020Y0867401
X1441571Y0870606
X1389771Y0870606
X1391620Y0867401
X1397171Y0870606
X1399020Y0867401
X1404571Y0870606
X1406420Y0867401
X1443420Y0867401
X1410121Y0873810
X1415671Y0870606
X1417520Y0873810
X1423071Y0870606
X1424921Y0873810
X1430471Y0870606
X1432320Y0873810
X1437871Y0870606
X1439720Y0873810
X1387920Y0873810
X1393471Y0870606
X1395320Y0873810
X1400871Y0870606
X1402720Y0873810
X1408271Y0870606
X1445271Y0870606
X1484120Y0963530
X1473020Y0893036
X1473020Y0963530
X1482271Y0966735
X1474871Y0966735
X1480420Y0969939
X1476720Y0969939
X1791383Y1188451
X1775241Y1195144
X1791383Y1191798
X1775241Y1191798
X1775241Y1201837
X1775241Y1208530
X1775241Y1185105
X1791383Y1198491
X1791383Y1205184
X1791383Y1114829
X1791383Y1151640
X1775241Y1084711
X1775241Y1121522
X1775241Y1158333
X1791383Y1118176
X1791383Y1154987
X1775241Y1118176
X1775241Y1154987
X1791383Y1101444
X1791383Y1108136
X1775241Y1104790
X1775241Y1111483
X1791383Y1124869
X1791383Y1131562
X1775241Y1128215
X1775241Y1134908
X1791383Y1138255
X1791383Y1144947
X1775241Y1141601
X1775241Y1148294
X1791383Y1161680
X1791383Y1168373
X1775241Y1165026
X1775241Y1171719
X1791383Y1175066
X1791383Y1181758
X1775241Y1178412
X1791383Y1088058
X1791383Y1094751
X1775241Y1091404
X1775241Y1098097
X1791383Y0984318
X1775241Y0987664
X1791383Y0991011
X1775241Y0994357
X1775241Y1021129
X1791383Y1078018
X1791383Y1081365
X1775241Y1081365
X1791083Y1051247
X1775241Y1054593
X1821083Y1051247
X1804941Y1054593
X1791383Y1064633
X1791383Y1071325
X1775241Y1067979
X1775241Y1074672
X1775241Y1027822
X1791383Y1031168
X1775241Y1034515
X1791383Y1037861
X1775241Y1041207
X1791383Y1044554
X1775241Y1047900
X1791383Y1024475
X1821083Y1024475
X1791383Y1021129
X1821083Y1021129
X1791383Y0970932
X1775241Y0937467
X1791383Y0893963
X1791383Y0930774
X1775241Y0900656
X1775241Y0934121
X1791383Y0897310
X1791383Y0934121
X1775241Y0897310
X1791383Y0887270
X1775241Y0883924
X1775241Y0890617
X1791383Y0904003
X1791383Y0910696
X1775241Y0907349
X1775241Y0914042
X1791383Y0940814
X1791383Y0947507
X1775241Y0944160
X1775241Y0950853
X1791383Y0917389
X1791383Y0924081
X1775241Y0920735
X1775241Y0927428
X1775241Y0974278
X1791383Y0977625
X1775241Y0980971
X1791383Y0857152
X1775241Y0790223
X1775241Y0863845
X1791383Y0786877
X1791383Y0860499
X1775241Y0786877
X1775241Y0860499
X1775241Y0870538
X1775241Y0877231
X1791383Y0880577
X1791383Y0793570
X1791383Y0800263
X1775241Y0796916
X1775241Y0803609
X1791383Y0843766
X1791383Y0850459
X1775241Y0847113
X1775241Y0853806
X1791383Y0867192
X1791383Y0873885
X1791383Y0783530
X1791383Y0770144
X1791383Y0776837
X1775241Y0773491
X1775241Y0780184
M00
X0117389Y0026474
X0124494Y0019538
X0153255Y0026474
X0160360Y0019538
X0167428Y0026474
X0074869Y0026474
X0081974Y0019538
X0089042Y0026474
X0096147Y0019538
X0103215Y0026474
X0110320Y0019538
X0120789Y0026474
X0127894Y0019538
X0156655Y0026474
X0163760Y0019538
X0170828Y0026474
X0078269Y0026474
X0085374Y0019538
X0092442Y0026474
X0099547Y0019538
X0106615Y0026474
X0113720Y0019538
X0170666Y1569968
X0074218Y1572504
X0167266Y1569968
X0077618Y1572504
X0264657Y1590094
X0192297Y1590094
X0204357Y1590094
X0216417Y1590094
X0228477Y1590094
X0240537Y1590094
X0252597Y1590094
X0261257Y1590094
X0188897Y1590094
X0200957Y1590094
X0213017Y1590094
X0225077Y1590094
X0237137Y1590094
X0249197Y1590094
X0174533Y0019538
X0197389Y0026474
X0204494Y0019538
X0211562Y0026474
X0218667Y0019538
X0177933Y0019538
X0200789Y0026474
X0207894Y0019538
X0214962Y0026474
X0222067Y0019538
X0276717Y1590094
X0288777Y1590094
X0300837Y1590094
X0312897Y1590094
X0324957Y1590094
X0337017Y1590094
X0349077Y1590094
X0361137Y1590094
X0273317Y1590094
X0285377Y1590094
X0297437Y1590094
X0309497Y1590094
X0321557Y1590094
X0333617Y1590094
X0345677Y1590094
X0357737Y1590094
X0369797Y1590094
X0373197Y1590094
X0545411Y1590094
X0557471Y1590094
X0569531Y1590094
X0473051Y1590094
X0485111Y1590094
X0497171Y1590094
X0509231Y1590094
X0521291Y1590094
X0533351Y1590094
X0548811Y1590094
X0560871Y1590094
X0476451Y1590094
X0488511Y1590094
X0500571Y1590094
X0512631Y1590094
X0524691Y1590094
X0536751Y1590094
X0581591Y1590094
X0593651Y1590094
X0605711Y1590094
X0617771Y1590094
X0629831Y1590094
X0641891Y1590094
X0653951Y1590094
X0572931Y1590094
X0584991Y1590094
X0597051Y1590094
X0609111Y1590094
X0621171Y1590094
X0633231Y1590094
X0645291Y1590094
X0657351Y1590094
X1205472Y1614292
X1217532Y1614292
X1229592Y1614292
X1241652Y1614292
X1253712Y1614292
X1265772Y1614292
X1202072Y1614292
X1214132Y1614292
X1226192Y1614292
X1238252Y1614292
X1250312Y1614292
X1262372Y1614292
X1277832Y1614292
X1289892Y1614292
X1301952Y1614292
X1314012Y1614292
X1326072Y1614292
X1338132Y1614292
X1350192Y1614292
X1362252Y1614292
X1274432Y1614292
X1286492Y1614292
X1298552Y1614292
X1310612Y1614292
X1322672Y1614292
X1334732Y1614292
X1346792Y1614292
X1358852Y1614292
X1370912Y1614292
X1465695Y1590094
X1462295Y1590094
X1374312Y1614292
X1386372Y1614292
X1382972Y1614292
X1552708Y0026431
X1559813Y0019495
X1566881Y0026431
X1549308Y0026431
X1556413Y0019495
X1563481Y0026431
X1570586Y0019495
X1534655Y1590094
X1546715Y1590094
X1558775Y1590094
X1570835Y1590094
X1474355Y1590094
X1486415Y1590094
X1498475Y1590094
X1510535Y1590094
X1522595Y1590094
X1538055Y1590094
X1550115Y1590094
X1562175Y1590094
X1477755Y1590094
X1489815Y1590094
X1501875Y1590094
X1513935Y1590094
X1525995Y1590094
X1582895Y1590094
X1594955Y1590094
X1607015Y1590094
X1619075Y1590094
X1631135Y1590094
X1643195Y1590094
X1574235Y1590094
X1586295Y1590094
X1598355Y1590094
X1610415Y1590094
X1622475Y1590094
X1634535Y1590094
X1646595Y1590094
X1595228Y0026431
X1602333Y0019495
X1631094Y0026431
X1638199Y0019495
X1645267Y0026431
X1652372Y0019495
X1573986Y0019495
X1581054Y0026431
X1588159Y0019495
X1591828Y0026431
X1598933Y0019495
X1627694Y0026431
X1634799Y0019495
X1641867Y0026431
X1648972Y0019495
X1671828Y0026431
X1577654Y0026431
X1584759Y0019495
X1675228Y0026431
X1682333Y0019495
X1689401Y0026431
X1693106Y0019495
X1678933Y0019495
X1686001Y0026431
X1696506Y0019495
M00
X0230906Y1696417
X0246654Y1696417
X0262402Y1696417
X0230906Y1691692
X0246654Y1691692
X0262402Y1691692
X0238780Y1700354
X0254528Y1700354
X0270276Y1700354
X0238780Y1695629
X0254528Y1695629
X0270276Y1695629
X0352953Y1700354
X0337205Y1700354
X0321457Y1700354
X0305709Y1700354
X0352953Y1695629
X0345079Y1696417
X0337205Y1695629
X0329331Y1696417
X0321457Y1695629
X0313583Y1696417
X0305709Y1695629
X0297835Y1696417
X0345079Y1691692
X0329331Y1691692
X0313583Y1691692
X0297835Y1691692
X0278150Y1696417
X0278150Y1691692
X0286024Y1700354
X0286024Y1695629
X0550197Y1681456
X0542323Y1682244
X0534449Y1681456
X0526575Y1682244
X0518701Y1681456
X0510827Y1682244
X0502953Y1681456
X0495079Y1682244
X0542323Y1677519
X0526575Y1677519
X0510827Y1677519
X0495079Y1677519
X0569882Y1681456
X0562008Y1682244
X0562008Y1677519
X0550197Y1686180
X0534449Y1686180
X0518701Y1686180
X0502953Y1686180
X0569882Y1686180
X0617126Y1686180
X0601378Y1686180
X0585630Y1686180
X0617126Y1681456
X0609252Y1682244
X0601378Y1681456
X0593504Y1682244
X0585630Y1681456
X0577756Y1682244
X0609252Y1677519
X0593504Y1677519
X0577756Y1677519
X1262402Y1700354
X1246654Y1700354
X1270276Y1696417
X1262402Y1695629
X1254528Y1696417
X1246654Y1695629
X1238780Y1696417
X1270276Y1691692
X1254528Y1691692
X1238780Y1691692
X1360827Y1700354
X1345079Y1700354
X1329331Y1700354
X1313583Y1700354
X1360827Y1695629
X1352953Y1696417
X1345079Y1695629
X1337205Y1696417
X1329331Y1695629
X1321457Y1696417
X1313583Y1695629
X1305709Y1696417
X1352953Y1691692
X1337205Y1691692
X1321457Y1691692
X1305709Y1691692
X1293898Y1700354
X1278150Y1700354
X1293898Y1695629
X1286024Y1696417
X1278150Y1695629
X1286024Y1691692
X1558071Y1681456
X1550197Y1682244
X1542323Y1681456
X1534449Y1682244
X1526575Y1681456
X1518701Y1682244
X1510827Y1681456
X1502953Y1682244
X1550197Y1677519
X1534449Y1677519
X1518701Y1677519
X1502953Y1677519
X1569882Y1682244
X1569882Y1677519
X1558071Y1686180
X1542323Y1686180
X1526575Y1686180
X1510827Y1686180
X1625000Y1686180
X1609252Y1686180
X1593504Y1686180
X1577756Y1686180
X1625000Y1681456
X1617126Y1682244
X1609252Y1681456
X1601378Y1682244
X1593504Y1681456
X1585630Y1682244
X1577756Y1681456
X1617126Y1677519
X1601378Y1677519
X1585630Y1677519
M30
